(kicad_pcb
	(version 20211014)
	(generator pcbnew)
	(general
    (thickness 1.6)
  )
	(paper "A4")
	(title_block
    (title "SA800U (Snapdragon 845) Baseboard")
    (date "2023-10-19")
    (rev "1.0.3")
    (company "Antmicro Ltd.")
    (comment 1 "www.antmicro.com")
		(comment 9 "footprints 57-57 of 589")
	)
	(layers
    (0 "F.Cu" signal)
    (1 "In1.Cu" power)
    (2 "In2.Cu" signal)
    (3 "In3.Cu" signal)
    (4 "In4.Cu" power)
    (31 "B.Cu" signal)
    (32 "B.Adhes" user "B.Adhesive")
    (33 "F.Adhes" user "F.Adhesive")
    (34 "B.Paste" user)
    (35 "F.Paste" user)
    (36 "B.SilkS" user "B.Silkscreen")
    (37 "F.SilkS" user "F.Silkscreen")
    (38 "B.Mask" user)
    (39 "F.Mask" user)
    (40 "Dwgs.User" user "User.Drawings")
    (41 "Cmts.User" user "User.Comments")
    (42 "Eco1.User" user "User.Eco1")
    (43 "Eco2.User" user "User.Eco2")
    (44 "Edge.Cuts" user)
    (45 "Margin" user)
    (46 "B.CrtYd" user "B.Courtyard")
    (47 "F.CrtYd" user "F.Courtyard")
    (48 "B.Fab" user)
    (49 "F.Fab" user)
  )
	(footprint "sa800u-baseboard-hw-footprints:R_0402_1005Metric" (layer "F.Cu")
    (tedit 5FD9C158)
    (at 144.95 94.4)
    (descr "Resistor SMD 0402")
    (tags "resistor SMD 0402")
    (property "Author" "Antmicro")
    (property "License" "Apache-2.0")
    (property "MPN" "CR0402-FX-2200GLF")
    (property "Manufacturer" "Bourns")
    (property "Sheetfile" "m2.kicad_sch")
    (property "Sheetname" "M2")
    (property "Tolerance" "1%")
    (property "Val" "220R")
    (attr smd)
    (fp_text reference "R92" (at -3.04 0.36) (layer "F.SilkS")
      (effects (font (size 0.7 0.7) (thickness 0.15)) (justify left bottom))
    )
    (fp_text value "R_220R_0402" (at 0 1.4) (layer "F.Fab")
      (effects (font (size 0.7 0.7) (thickness 0.15)) (justify left bottom))
    )
    (fp_text user "Author: Antmicro" (at -0.95 4.169) (layer "F.Fab") hide
      (effects (font (size 0.7 0.7) (thickness 0.15)) (justify left bottom))
    )
    (fp_text user "${REFERENCE}" (at -0.95 3.168) (layer "F.Fab") hide
      (effects (font (size 0.7 0.7) (thickness 0.15)) (justify left bottom))
    )
    (fp_text user "License: Apache-2.0" (at -0.95 5.169) (layer "F.Fab") hide
      (effects (font (size 0.7 0.7) (thickness 0.15)) (justify left bottom))
    )
    (fp_rect (start -0.93 -0.47) (end 0.93 0.47) (layer "F.CrtYd") (width 0.05) (fill none))
    (fp_rect (start -0.5 -0.25) (end 0.5 0.25) (layer "F.Fab") (width 0.15) (fill none))
    (pad "1" smd roundrect (at -0.485 0) (size 0.59 0.64) (layers "F.Cu" "F.Paste" "F.Mask") (roundrect_rratio 0.25)
      (net 131 "3V3_SYS") (pintype "passive"))
    (pad "2" smd roundrect (at 0.485 0) (size 0.59 0.64) (layers "F.Cu" "F.Paste" "F.Mask") (roundrect_rratio 0.25)
      (net 373 "Net-(D21-Pad1)") (pintype "passive"))
  )
)
